(kicad_pcb
	(version 20241229)
	(generator "pcbnew")
	(generator_version "9.0")
	(general
		(thickness 1.711)
		(legacy_teardrops no)
	)
	(paper "A4")
	(title_block
		(title "Antmicro Baseboard for Jetson AGX Thor")
		(date "2026-02-18")
		(rev "1.1.0")
		(company "Antmicro Ltd")
		(comment 1 "www.antmicro.com")
		(comment 9 "footprints 634-637 of 1170")
	)
	(layers
		(0 "F.Cu" signal)
		(4 "In1.Cu" signal)
		(6 "In2.Cu" signal)
		(8 "In3.Cu" signal)
		(10 "In4.Cu" jumper)
		(12 "In5.Cu" signal)
		(14 "In6.Cu" signal)
		(16 "In7.Cu" signal)
		(18 "In8.Cu" signal)
		(2 "B.Cu" signal)
		(9 "F.Adhes" user "F.Adhesive")
		(11 "B.Adhes" user "B.Adhesive")
		(13 "F.Paste" user)
		(15 "B.Paste" user)
		(5 "F.SilkS" user "F.Silkscreen")
		(7 "B.SilkS" user "B.Silkscreen")
		(1 "F.Mask" user)
		(3 "B.Mask" user)
		(17 "Dwgs.User" user "User.Drawings")
		(19 "Cmts.User" user "User.Comments")
		(21 "Eco1.User" user "User.Eco1")
		(23 "Eco2.User" user "User.Eco2")
		(25 "Edge.Cuts" user)
		(27 "Margin" user)
		(31 "F.CrtYd" user "F.Courtyard")
		(29 "B.CrtYd" user "B.Courtyard")
		(35 "F.Fab" user)
		(33 "B.Fab" user)
	)
	(footprint "antmicro-footprints:C_0402_1005Metric"
		(layer "B.Cu")
		(at 96.68 105.51 90)
		(descr "Capacitor SMD 0402")
		(tags "capacitor SMD 0402")
		(property "Reference" "C332"
			(at -3.69 -0.28 90)
			(layer "B.SilkS")
			(effects
				(font
					(size 0.7 0.7)
					(thickness 0.15)
				)
				(justify right top mirror)
			)
		)
		(property "Value" "C_100n_0402"
			(at -1.022927 -2.155213 90)
			(layer "B.Fab")
			(effects
				(font
					(size 0.7 0.7)
					(thickness 0.15)
				)
				(justify right top mirror)
			)
		)
		(property "Datasheet" "https://www.murata.com/products/productdetail?partno=GRM155R61H104KE14%23"
			(at 0 0 90)
			(layer "B.Fab")
			(hide yes)
			(effects
				(font
					(size 1.27 1.27)
					(thickness 0.15)
				)
				(justify mirror)
			)
		)
		(property "Description" "SMD Multilayer Ceramic Capacitor, 0.1 µF, 50 V, 0402 [1005 Metric], ± 10%, X5R, GRM Series"
			(at 0 0 90)
			(layer "B.Fab")
			(hide yes)
			(effects
				(font
					(size 1.27 1.27)
					(thickness 0.15)
				)
				(justify mirror)
			)
		)
		(property "Manufacturer" "Murata"
			(at 0 0 270)
			(unlocked yes)
			(layer "B.Fab")
			(hide yes)
			(effects
				(font
					(size 1 1)
					(thickness 0.15)
				)
				(justify mirror)
			)
		)
		(property "MPN" "GRM155R61H104KE14D"
			(at 0 0 270)
			(unlocked yes)
			(layer "B.Fab")
			(hide yes)
			(effects
				(font
					(size 1 1)
					(thickness 0.15)
				)
				(justify mirror)
			)
		)
		(property "Val" "100n"
			(at 0 0 270)
			(unlocked yes)
			(layer "B.Fab")
			(hide yes)
			(effects
				(font
					(size 1 1)
					(thickness 0.15)
				)
				(justify mirror)
			)
		)
		(property "License" "Apache-2.0"
			(at 0 0 270)
			(unlocked yes)
			(layer "B.Fab")
			(hide yes)
			(effects
				(font
					(size 1 1)
					(thickness 0.15)
				)
				(justify mirror)
			)
		)
		(property "Author" "Antmicro"
			(at 0 0 270)
			(unlocked yes)
			(layer "B.Fab")
			(hide yes)
			(effects
				(font
					(size 1 1)
					(thickness 0.15)
				)
				(justify mirror)
			)
		)
		(property "Voltage" "50V"
			(at 0 0 270)
			(unlocked yes)
			(layer "B.Fab")
			(hide yes)
			(effects
				(font
					(size 1 1)
					(thickness 0.15)
				)
				(justify mirror)
			)
		)
		(property "Dielectric" "X5R"
			(at 0 0 270)
			(unlocked yes)
			(layer "B.Fab")
			(hide yes)
			(effects
				(font
					(size 1 1)
					(thickness 0.15)
				)
				(justify mirror)
			)
		)
		(sheetname "/SoM_IO2/")
		(sheetfile "som_io2.kicad_sch")
		(attr smd)
		(fp_poly
			(pts
				(xy -0.925 0.47) (xy 0.925 0.47) (xy 0.925 -0.47) (xy -0.925 -0.47)
			)
			(stroke
				(width 0.05)
				(type default)
			)
			(fill no)
			(layer "B.CrtYd")
		)
		(fp_line
			(start 0.504 -0.248)
			(end -0.494 -0.248)
			(stroke
				(width 0.15)
				(type solid)
			)
			(layer "B.Fab")
		)
		(fp_line
			(start -0.494 -0.248)
			(end -0.494 0.25)
			(stroke
				(width 0.15)
				(type solid)
			)
			(layer "B.Fab")
		)
		(fp_line
			(start 0.504 0.25)
			(end 0.504 -0.248)
			(stroke
				(width 0.15)
				(type solid)
			)
			(layer "B.Fab")
		)
		(fp_line
			(start -0.494 0.25)
			(end 0.504 0.25)
			(stroke
				(width 0.15)
				(type solid)
			)
			(layer "B.Fab")
		)
		(fp_text user "Author: Antmicro"
			(at -0.939 -3.399 90)
			(layer "B.Fab")
			(effects
				(font
					(size 0.7 0.7)
					(thickness 0.15)
				)
				(justify right top mirror)
			)
		)
		(fp_text user "${REFERENCE}"
			(at -0.939 -4.599 90)
			(layer "B.Fab")
			(effects
				(font
					(size 0.7 0.7)
					(thickness 0.15)
				)
				(justify right top mirror)
			)
		)
		(fp_text user "License: Apache-2.0"
			(at -0.939 -5.799 90)
			(layer "B.Fab")
			(effects
				(font
					(size 0.7 0.7)
					(thickness 0.15)
				)
				(justify right top mirror)
			)
		)
		(pad "1" smd roundrect
			(at -0.48 0 90)
			(size 0.59 0.64)
			(layers "B.Cu" "B.Mask" "B.Paste")
			(roundrect_rratio 0.25)
			(net 1252 "/SoM_IO2/DP1.AUX_C+")
			(pintype "passive")
		)
		(pad "2" smd roundrect
			(at 0.48 0 90)
			(size 0.59 0.64)
			(layers "B.Cu" "B.Mask" "B.Paste")
			(roundrect_rratio 0.25)
			(net 729 "/Expansion connector/DP1.AUX+")
			(pintype "passive")
		)
	)
	(footprint "antmicro-footprints:R_0402_1005Metric"
		(layer "B.Cu")
		(at 207 65.98)
		(descr "Resistor SMD 0402")
		(tags "resistor SMD 0402")
		(property "Reference" "R179"
			(at -3.909 -0.476 0)
			(layer "B.SilkS")
			(effects
				(font
					(size 0.7 0.7)
					(thickness 0.15)
				)
				(justify right top mirror)
			)
		)
		(property "Value" "R_4k7_0402"
			(at -1.011843 -1.772046 0)
			(layer "B.Fab")
			(effects
				(font
					(size 0.7 0.7)
					(thickness 0.15)
				)
				(justify right top mirror)
			)
		)
		(property "Datasheet" "https://www.bourns.com/docs/product-datasheets/cr.pdf"
			(at 0 0 0)
			(layer "B.Fab")
			(hide yes)
			(effects
				(font
					(size 1.27 1.27)
					(thickness 0.15)
				)
				(justify mirror)
			)
		)
		(property "Description" "SMD Chip Resistor, 4.7 kohm, ± 1%, 62.5 mW, 0402 [1005 Metric], Thick Film, General Purpose"
			(at 0 0 0)
			(layer "B.Fab")
			(hide yes)
			(effects
				(font
					(size 1.27 1.27)
					(thickness 0.15)
				)
				(justify mirror)
			)
		)
		(property "Manufacturer" "Bourns"
			(at 0 0 180)
			(unlocked yes)
			(layer "B.Fab")
			(hide yes)
			(effects
				(font
					(size 1 1)
					(thickness 0.15)
				)
				(justify mirror)
			)
		)
		(property "MPN" "CR0402-FX-4701GLF"
			(at 0 0 180)
			(unlocked yes)
			(layer "B.Fab")
			(hide yes)
			(effects
				(font
					(size 1 1)
					(thickness 0.15)
				)
				(justify mirror)
			)
		)
		(property "Val" "4k7"
			(at 0 0 180)
			(unlocked yes)
			(layer "B.Fab")
			(hide yes)
			(effects
				(font
					(size 1 1)
					(thickness 0.15)
				)
				(justify mirror)
			)
		)
		(property "License" "Apache-2.0"
			(at 0 0 180)
			(unlocked yes)
			(layer "B.Fab")
			(hide yes)
			(effects
				(font
					(size 1 1)
					(thickness 0.15)
				)
				(justify mirror)
			)
		)
		(property "Author" "Antmicro"
			(at 0 0 180)
			(unlocked yes)
			(layer "B.Fab")
			(hide yes)
			(effects
				(font
					(size 1 1)
					(thickness 0.15)
				)
				(justify mirror)
			)
		)
		(property "Tolerance" "1%"
			(at 0 0 180)
			(unlocked yes)
			(layer "B.Fab")
			(hide yes)
			(effects
				(font
					(size 1 1)
					(thickness 0.15)
				)
				(justify mirror)
			)
		)
		(sheetname "/CSI/")
		(sheetfile "csi.kicad_sch")
		(attr smd)
		(fp_poly
			(pts
				(xy -0.925 0.47) (xy -0.925 -0.47) (xy 0.925 -0.47) (xy 0.925 0.47)
			)
			(stroke
				(width 0.05)
				(type default)
			)
			(fill no)
			(layer "B.CrtYd")
		)
		(fp_poly
			(pts
				(xy -0.5 0.25) (xy -0.5 -0.25) (xy 0.5 -0.25) (xy 0.5 0.25)
			)
			(stroke
				(width 0.15)
				(type solid)
			)
			(fill no)
			(layer "B.Fab")
		)
		(fp_text user "${REFERENCE}"
			(at -0.95 -3.168 0)
			(layer "B.Fab")
			(effects
				(font
					(size 0.7 0.7)
					(thickness 0.15)
				)
				(justify right top mirror)
			)
		)
		(fp_text user "Author: Antmicro"
			(at -0.95 -4.169 0)
			(layer "B.Fab")
			(effects
				(font
					(size 0.7 0.7)
					(thickness 0.15)
				)
				(justify right top mirror)
			)
		)
		(fp_text user "License: Apache-2.0"
			(at -0.949999 -5.169 0)
			(layer "B.Fab")
			(effects
				(font
					(size 0.7 0.7)
					(thickness 0.15)
				)
				(justify right top mirror)
			)
		)
		(pad "1" smd roundrect
			(at -0.48 0)
			(size 0.59 0.64)
			(layers "B.Cu" "B.Mask" "B.Paste")
			(roundrect_rratio 0.25)
			(net 1 "GND")
			(pintype "passive")
		)
		(pad "2" smd roundrect
			(at 0.48 0)
			(size 0.59 0.64)
			(layers "B.Cu" "B.Mask" "B.Paste")
			(roundrect_rratio 0.25)
			(net 997 "/CSI/CSIB_5V_ISET")
			(pintype "passive")
		)
	)
	(footprint "antmicro-footprints:SOT-523"
		(layer "B.Cu")
		(at 220.532132 97.092 -90)
		(property "Reference" "Q34"
			(at 2.008 -1.067868 0)
			(layer "B.SilkS")
			(effects
				(font
					(size 0.7 0.7)
					(thickness 0.15)
				)
				(justify left bottom mirror)
			)
		)
		(property "Value" "DMG1012T-7"
			(at 0.1 -1.824 90)
			(layer "B.Fab")
			(effects
				(font
					(size 0.7 0.7)
					(thickness 0.15)
				)
				(justify left bottom mirror)
			)
		)
		(property "Datasheet" "https://www.diodes.com/assets/Datasheets/ds31783.pdf"
			(at 0 0 90)
			(layer "B.Fab")
			(hide yes)
			(effects
				(font
					(size 1.27 1.27)
					(thickness 0.15)
				)
				(justify mirror)
			)
		)
		(property "Description" "Power MOSFET, N Channel, 20 V, 630 mA, 0.3 ohm, SOT-523, Surface Mount"
			(at 0 0 90)
			(layer "B.Fab")
			(hide yes)
			(effects
				(font
					(size 1.27 1.27)
					(thickness 0.15)
				)
				(justify mirror)
			)
		)
		(property "MPN" "DMG1012T-7"
			(at 0 0 90)
			(unlocked yes)
			(layer "B.Fab")
			(hide yes)
			(effects
				(font
					(size 1 1)
					(thickness 0.15)
				)
				(justify mirror)
			)
		)
		(property "Manufacturer" "Diodes Incorporated"
			(at 0 0 90)
			(unlocked yes)
			(layer "B.Fab")
			(hide yes)
			(effects
				(font
					(size 1 1)
					(thickness 0.15)
				)
				(justify mirror)
			)
		)
		(property "Author" "Antmicro"
			(at 0 0 90)
			(unlocked yes)
			(layer "B.Fab")
			(hide yes)
			(effects
				(font
					(size 1 1)
					(thickness 0.15)
				)
				(justify mirror)
			)
		)
		(property "License" "Apache-2.0"
			(at 0 0 90)
			(unlocked yes)
			(layer "B.Fab")
			(hide yes)
			(effects
				(font
					(size 1 1)
					(thickness 0.15)
				)
				(justify mirror)
			)
		)
		(sheetname "/USB DP Alt mode/")
		(sheetfile "usb_dp.kicad_sch")
		(attr smd)
		(fp_line
			(start -0.725 0.551)
			(end -0.277 0.551)
			(stroke
				(width 0.15)
				(type solid)
			)
			(layer "B.SilkS")
		)
		(fp_line
			(start -0.277 0.551)
			(end -0.277 0.75)
			(stroke
				(width 0.15)
				(type solid)
			)
			(layer "B.SilkS")
		)
		(fp_line
			(start -0.927 0.351)
			(end -0.725 0.551)
			(stroke
				(width 0.15)
				(type solid)
			)
			(layer "B.SilkS")
		)
		(fp_line
			(start -0.927 0.051)
			(end -0.927 0.351)
			(stroke
				(width 0.15)
				(type solid)
			)
			(layer "B.SilkS")
		)
		(fp_circle
			(center -0.9652 -0.9652)
			(end -0.9152 -0.9652)
			(stroke
				(width 0.15)
				(type solid)
			)
			(fill yes)
			(layer "B.SilkS")
		)
		(fp_line
			(start -1.12 1.16)
			(end 1.1 1.16)
			(stroke
				(width 0.05)
				(type solid)
			)
			(layer "B.CrtYd")
		)
		(fp_line
			(start -1.12 1.16)
			(end -1.12 -1.15)
			(stroke
				(width 0.05)
				(type solid)
			)
			(layer "B.CrtYd")
		)
		(fp_line
			(start 1.1 1.16)
			(end 1.1 -1.15)
			(stroke
				(width 0.05)
				(type solid)
			)
			(layer "B.CrtYd")
		)
		(fp_line
			(start -1.12 -1.15)
			(end 1.1 -1.15)
			(stroke
				(width 0.05)
				(type solid)
			)
			(layer "B.CrtYd")
		)
		(fp_line
			(start -0.652 0.425)
			(end -0.802 0.276)
			(stroke
				(width 0.15)
				(type solid)
			)
			(layer "B.Fab")
		)
		(fp_line
			(start 0.8 0.425)
			(end -0.652 0.425)
			(stroke
				(width 0.15)
				(type solid)
			)
			(layer "B.Fab")
		)
		(fp_line
			(start 0.8 0.425)
			(end 0.8 -0.424)
			(stroke
				(width 0.15)
				(type solid)
			)
			(layer "B.Fab")
		)
		(fp_line
			(start -0.802 0.276)
			(end -0.802 -0.424)
			(stroke
				(width 0.15)
				(type solid)
			)
			(layer "B.Fab")
		)
		(fp_line
			(start 0.8 -0.424)
			(end -0.802 -0.424)
			(stroke
				(width 0.15)
				(type solid)
			)
			(layer "B.Fab")
		)
		(fp_circle
			(center -0.9652 -0.9652)
			(end -0.9144 -0.9652)
			(stroke
				(width 0.15)
				(type solid)
			)
			(fill no)
			(layer "B.Fab")
		)
		(fp_text user "${REFERENCE}"
			(at -1.12 -3.824 90)
			(layer "B.Fab")
			(effects
				(font
					(size 0.7 0.7)
					(thickness 0.15)
				)
				(justify left bottom mirror)
			)
		)
		(fp_text user "Author: Antmicro"
			(at -1.12 -6.224 90)
			(layer "B.Fab")
			(effects
				(font
					(size 0.7 0.7)
					(thickness 0.15)
				)
				(justify left bottom mirror)
			)
		)
		(fp_text user "License: Apache-2.0"
			(at -1.12 -5.024 90)
			(layer "B.Fab")
			(effects
				(font
					(size 0.7 0.7)
					(thickness 0.15)
				)
				(justify left bottom mirror)
			)
		)
		(pad "1" smd rect
			(at -0.5 -0.65 270)
			(size 0.4 0.51)
			(layers "B.Cu" "B.Mask" "B.Paste")
			(net 957 "/USB DP Alt mode/HPDIN")
			(pinfunction "G")
			(pintype "input")
		)
		(pad "2" smd rect
			(at 0.498 -0.65 270)
			(size 0.4 0.51)
			(layers "B.Cu" "B.Mask" "B.Paste")
			(net 1 "GND")
			(pinfunction "S")
			(pintype "passive")
		)
		(pad "3" smd rect
			(at 0 0.652 270)
			(size 0.4 0.51)
			(layers "B.Cu" "B.Mask" "B.Paste")
			(net 1300 "Net-(Q34-D)")
			(pinfunction "D")
			(pintype "passive")
		)
	)
	(footprint "antmicro-footprints:R_0402_1005Metric"
		(layer "B.Cu")
		(at 219.88 119.9)
		(descr "Resistor SMD 0402")
		(tags "resistor SMD 0402")
		(property "Reference" "R333"
			(at -1.66 -1.5 0)
			(layer "B.SilkS")
			(effects
				(font
					(size 0.7 0.7)
					(thickness 0.15)
				)
				(justify right top mirror)
			)
		)
		(property "Value" "R_10k_0402"
			(at -1.011843 -1.772047 0)
			(layer "B.Fab")
			(effects
				(font
					(size 0.7 0.7)
					(thickness 0.15)
				)
				(justify right top mirror)
			)
		)
		(property "Datasheet" "https://www.bourns.com/docs/product-datasheets/cr.pdf"
			(at 0 0 0)
			(layer "B.Fab")
			(hide yes)
			(effects
				(font
					(size 1.27 1.27)
					(thickness 0.15)
				)
				(justify mirror)
			)
		)
		(property "Description" "SMD Chip Resistor, 10 kohm, ± 1%, 62.5 mW, 0402 [1005 Metric], Thick Film, General Purpose"
			(at 0 0 0)
			(layer "B.Fab")
			(hide yes)
			(effects
				(font
					(size 1.27 1.27)
					(thickness 0.15)
				)
				(justify mirror)
			)
		)
		(property "MPN" "CR0402-FX-1002GLF"
			(at 0 0 180)
			(unlocked yes)
			(layer "B.Fab")
			(hide yes)
			(effects
				(font
					(size 1 1)
					(thickness 0.15)
				)
				(justify mirror)
			)
		)
		(property "Manufacturer" "Bourns"
			(at 0 0 180)
			(unlocked yes)
			(layer "B.Fab")
			(hide yes)
			(effects
				(font
					(size 1 1)
					(thickness 0.15)
				)
				(justify mirror)
			)
		)
		(property "License" "Apache-2.0"
			(at 0 0 180)
			(unlocked yes)
			(layer "B.Fab")
			(hide yes)
			(effects
				(font
					(size 1 1)
					(thickness 0.15)
				)
				(justify mirror)
			)
		)
		(property "Author" "Antmicro"
			(at 0 0 180)
			(unlocked yes)
			(layer "B.Fab")
			(hide yes)
			(effects
				(font
					(size 1 1)
					(thickness 0.15)
				)
				(justify mirror)
			)
		)
		(property "Val" "10k"
			(at 0 0 180)
			(unlocked yes)
			(layer "B.Fab")
			(hide yes)
			(effects
				(font
					(size 1 1)
					(thickness 0.15)
				)
				(justify mirror)
			)
		)
		(property "Tolerance" "1%"
			(at 0 0 180)
			(unlocked yes)
			(layer "B.Fab")
			(hide yes)
			(effects
				(font
					(size 1 1)
					(thickness 0.15)
				)
				(justify mirror)
			)
		)
		(sheetname "/USB Hub/")
		(sheetfile "usb_hub.kicad_sch")
		(attr smd)
		(fp_rect
			(start -0.925 0.47)
			(end 0.925 -0.47)
			(stroke
				(width 0.05)
				(type default)
			)
			(fill no)
			(layer "B.CrtYd")
		)
		(fp_rect
			(start -0.5 0.25)
			(end 0.5 -0.25)
			(stroke
				(width 0.15)
				(type solid)
			)
			(fill no)
			(layer "B.Fab")
		)
		(fp_text user "License: Apache-2.0"
			(at -0.95 -5.169 0)
			(layer "B.Fab")
			(effects
				(font
					(size 0.7 0.7)
					(thickness 0.15)
				)
				(justify right top mirror)
			)
		)
		(fp_text user "Author: Antmicro"
			(at -0.95 -4.169 0)
			(layer "B.Fab")
			(effects
				(font
					(size 0.7 0.7)
					(thickness 0.15)
				)
				(justify right top mirror)
			)
		)
		(fp_text user "${REFERENCE}"
			(at -0.95 -3.168 0)
			(layer "B.Fab")
			(effects
				(font
					(size 0.7 0.7)
					(thickness 0.15)
				)
				(justify right top mirror)
			)
		)
		(pad "1" smd roundrect
			(at -0.48 0)
			(size 0.59 0.64)
			(layers "B.Cu" "B.Mask" "B.Paste")
			(roundrect_rratio 0.25)
			(net 5 "+5V")
			(pintype "passive")
		)
		(pad "2" smd roundrect
			(at 0.48 0)
			(size 0.59 0.64)
			(layers "B.Cu" "B.Mask" "B.Paste")
			(roundrect_rratio 0.25)
			(net 1333 "Net-(Q29-D1)")
			(pintype "passive")
		)
	)
)
